# BASEBOARD_FAB2 (Tioga Pass) — schematic netlist excerpt (pin names and nets, part order shuffled) for the footprints in the layout excerpt that follows; sources: Cadence DE-HDL packaged netlist, KiCad conversion of Wiwynn_Tioga_Pass_MB.brd

T1D21  TEST-PAD-12P-1-GP-U  pkg DISCRET-GB1  page 258
  DP  = L12_85OHM_10INCH_DP
  DN  = L12_85OHM_10INCH_DN
  GND(0)  = GND
  GND(1)  = GND
  GND(2)  = GND
  GND(3)  = GND
  GND(4)  = GND
  GND(5)  = GND
  GND(6)  = GND
  GND(7)  = GND
  GND(8)  = GND
  GND(9)  = GND

Q1W4  FET_N_DUAL  2N7002DW FET  pkg SMLF  page 250
  SOURCE(0)  = GND
  GATE(0)  = FM_OCP_MEZZC_PRES_N
  DRAIN(0)  = FM_OCP_MEZZC_PRES_1V05_PCH_N
  SOURCE(0)  = GND
  GATE(0)  = FM_OCP_MEZZC_PRES_LVT3_BMC
  DRAIN(0)  = FM_OCP_MEZZC_PRES_LVT3_BMC

(kicad_pcb
	(version 20260206)
	(generator "pcbnew")
	(generator_version "10.0")
	(general
		(thickness 1.6)
		(legacy_teardrops no)
	)
	(paper "A4")
	(title_block
		(title "Wiwynn_Tioga_Pass_MB.brd")
		(comment 1 "Tioga Pass / footprints 1278-1279 of 4770")
	)
	(layers
		(0 "F.Cu" signal "TOP")
		(4 "In1.Cu" signal "L2GND")
		(6 "In2.Cu" signal "L3")
		(8 "In3.Cu" signal "L4GND")
		(10 "In4.Cu" signal "L5")
		(12 "In5.Cu" signal "L6GND")
		(14 "In6.Cu" signal "L7VCC")
		(16 "In7.Cu" signal "L8VCC")
		(18 "In8.Cu" signal "L9GND")
		(20 "In9.Cu" signal "L10")
		(22 "In10.Cu" signal "L11GND")
		(24 "In11.Cu" signal "L12")
		(26 "In12.Cu" signal "L13GND")
		(2 "B.Cu" signal "BOTTOM")
		(9 "F.Adhes" user "F.Adhesive")
		(11 "B.Adhes" user "B.Adhesive")
		(13 "F.Paste" user "Package Geometry/Pastemask Top")
		(15 "B.Paste" user "Package Geometry/Pastemask Bottom")
		(5 "F.SilkS" user "Ref Des/Silkscreen Top")
		(7 "B.SilkS" user "Ref Des/Silkscreen Bottom")
		(1 "F.Mask" user "Board Geometry/Soldermask Top")
		(3 "B.Mask" user "Board Geometry/Soldermask Bottom")
		(17 "Dwgs.User" user "User.Drawings")
		(19 "Cmts.User" user "User.Comments")
		(21 "Eco1.User" user "User.Eco1")
		(23 "Eco2.User" user "User.Eco2")
		(25 "Edge.Cuts" user "Board Geometry/Outline")
		(27 "Margin" user)
		(31 "F.CrtYd" user "Package Geometry/Place Bound Top")
		(29 "B.CrtYd" user "Package Geometry/Place Bound Bottom")
		(35 "F.Fab" user "Ref Des/Assembly Top")
		(33 "B.Fab" user "Ref Des/Assembly Bottom")
	)
	(footprint ""
		(layer "F.Cu")
		(at 416.402012 -52.738782)
		(property "Reference" "Q1W4"
			(at 0 -0.81788 0)
			(unlocked yes)
			(layer "F.SilkS")
			(effects
				(font
					(size 0.4064 0.254)
					(thickness 0.1524)
				)
				(justify left)
			)
		)
		(property "Value" ""
			(at 0 0 0)
			(layer "F.Fab")
			(effects
				(font
					(size 1.27 1.27)
				)
			)
		)
		(duplicate_pad_numbers_are_jumpers no)
		(fp_circle
			(center -0.848614 -0.6477)
			(end -0.721614 -0.6477)
			(stroke
				(width 0.254)
				(type default)
			)
			(fill no)
			(layer "F.SilkS")
		)
		(fp_poly
			(pts
				(xy 0.21463 -0.450088) (xy 1.56337 -0.450088) (xy 1.56337 1.75006) (xy 0.21463 1.75006)
			)
			(stroke
				(width 0)
				(type default)
			)
			(fill no)
			(layer "F.CrtYd")
		)
		(fp_line
			(start 0.21463 -0.450088)
			(end 1.56337 -0.450088)
			(stroke
				(width 0.1)
				(type default)
			)
			(layer "F.Fab")
		)
		(fp_line
			(start 0.21463 1.75006)
			(end 0.21463 -0.450088)
			(stroke
				(width 0.1)
				(type default)
			)
			(layer "F.Fab")
		)
		(fp_line
			(start 1.56337 -0.450088)
			(end 1.56337 1.75006)
			(stroke
				(width 0.1)
				(type default)
			)
			(layer "F.Fab")
		)
		(fp_line
			(start 1.56337 1.75006)
			(end 0.21463 1.75006)
			(stroke
				(width 0.1)
				(type default)
			)
			(layer "F.Fab")
		)
		(fp_circle
			(center -0.848614 -0.6477)
			(end -0.721614 -0.6477)
			(stroke
				(width 0.254)
				(type default)
			)
			(fill no)
			(layer "F.Fab")
		)
		(pad "1" smd rect
			(at 0 0)
			(size 1.016 0.381)
			(layers "F.Cu" "F.Mask" "F.Paste")
			(net "GND")
		)
		(pad "2" smd rect
			(at 0 0.649986)
			(size 1.016 0.381)
			(layers "F.Cu" "F.Mask" "F.Paste")
			(net "FM_OCP_MEZZC_PRES_N")
		)
		(pad "3" smd rect
			(at 0 1.299972)
			(size 1.016 0.381)
			(layers "F.Cu" "F.Mask" "F.Paste")
			(net "FM_OCP_MEZZC_PRES_1V05_PCH_N")
		)
		(pad "4" smd rect
			(at 1.778 1.299972)
			(size 1.016 0.381)
			(layers "F.Cu" "F.Mask" "F.Paste")
			(net "GND")
		)
		(pad "5" smd rect
			(at 1.778 0.649986)
			(size 1.016 0.381)
			(layers "F.Cu" "F.Mask" "F.Paste")
			(net "FM_OCP_MEZZC_PRES_LVT3_BMC")
		)
		(pad "6" smd rect
			(at 1.778 0)
			(size 1.016 0.381)
			(layers "F.Cu" "F.Mask" "F.Paste")
			(net "FM_OCP_MEZZC_PRES_LVT3_BMC")
		)
	)
	(footprint ""
		(layer "F.Cu")
		(at 236.715808 -164.90188 -90)
		(property "Reference" "T1D21"
			(at 0 0 270)
			(layer "F.SilkS")
			(hide yes)
			(effects
				(font
					(size 1.27 1.27)
				)
			)
		)
		(property "Value" "*"
			(at -3.4036 -4.46405 270)
			(unlocked yes)
			(layer "F.Fab")
			(hide yes)
			(effects
				(font
					(size 0.889 0.889)
					(thickness 0.1524)
				)
			)
		)
		(property "Device Type" "TEST-PAD-12P-1-GP-U_DISCRET-GBA"
			(at -3.4036 -5.98805 270)
			(unlocked yes)
			(layer "F.Fab")
			(hide yes)
			(effects
				(font
					(size 0.889 0.889)
					(thickness 0.1524)
				)
			)
		)
		(duplicate_pad_numbers_are_jumpers no)
		(fp_line
			(start -2.3876 3.4798)
			(end -2.3876 -4.826)
			(stroke
				(width 0.1524)
				(type default)
			)
			(layer "F.SilkS")
		)
		(fp_line
			(start 2.3622 3.4798)
			(end -2.3876 3.4798)
			(stroke
				(width 0.1524)
				(type default)
			)
			(layer "F.SilkS")
		)
		(fp_line
			(start -2.3876 -4.826)
			(end 2.3622 -4.826)
			(stroke
				(width 0.1524)
				(type default)
			)
			(layer "F.SilkS")
		)
		(fp_line
			(start 2.3622 -4.826)
			(end 2.3622 3.4798)
			(stroke
				(width 0.1524)
				(type default)
			)
			(layer "F.SilkS")
		)
		(fp_rect
			(start -2.6416 3.7338)
			(end 2.6162 -5.08)
			(stroke
				(width 0)
				(type default)
			)
			(fill no)
			(layer "F.CrtYd")
		)
		(fp_rect
			(start -2.6416 3.7338)
			(end 2.6162 -5.08)
			(stroke
				(width 0)
				(type default)
			)
			(fill no)
			(layer "F.Fab")
		)
		(pad "1" smd circle
			(at 0.496824 -1.301496 270)
			(size 0.6604 0.6604)
			(layers "F.Cu" "F.Mask" "F.Paste")
			(net "L12_85OHM_10INCH_DP")
		)
		(pad "2" smd circle
			(at -0.503936 -1.301496 270)
			(size 0.6604 0.6604)
			(layers "F.Cu" "F.Mask" "F.Paste")
			(net "L12_85OHM_10INCH_DN")
		)
		(pad "3" smd custom
			(at -0.00889 0.370078 270)
			(size 0.74295 0.74295)
			(layers "F.Cu" "F.Mask" "F.Paste")
			(net "GND")
			(options
				(clearance outline)
				(anchor circle)
			)
			(primitives
				(gr_poly
					(pts
						(xy -2.1209 1.4859) (xy 2.1209 1.4859) (xy 2.1209 -1.4859) (xy 1.08585 -1.4859) (xy 1.08585 -0.4699)
						(xy -1.08585 -0.4699) (xy -1.08585 -1.4859) (xy -2.1209 -1.4859)
					)
					(width 0)
					(fill yes)
				)
			)
		)
		(pad "4" thru_hole circle
			(at 1.266444 -3.851656 270)
			(size 1.4478 1.4478)
			(drill 1.0414)
			(layers "*.Cu" "*.Mask")
			(remove_unused_layers no)
			(net "GND")
			(clearance 0.1524)
			(thermal_gap 0.1524)
		)
		(pad "5" thru_hole circle
			(at -1.273556 -3.851656 270)
			(size 1.4478 1.4478)
			(drill 1.0414)
			(layers "*.Cu" "*.Mask")
			(remove_unused_layers no)
			(net "GND")
			(clearance 0.1524)
			(thermal_gap 0.1524)
		)
		(pad "6" thru_hole circle
			(at 1.266444 2.498344 270)
			(size 1.4478 1.4478)
			(drill 1.0414)
			(layers "*.Cu" "*.Mask")
			(remove_unused_layers no)
			(net "GND")
			(clearance 0.1524)
			(thermal_gap 0.1524)
		)
		(pad "7" thru_hole circle
			(at -1.273556 2.498344 270)
			(size 1.4478 1.4478)
			(drill 1.0414)
			(layers "*.Cu" "*.Mask")
			(remove_unused_layers no)
			(net "GND")
			(clearance 0.1524)
			(thermal_gap 0.1524)
		)
		(pad "8" thru_hole circle
			(at 1.27 -0.4572 270)
			(size 0.7112 0.7112)
			(drill 0.4064)
			(layers "*.Cu" "*.Mask")
			(remove_unused_layers no)
			(net "GND")
			(clearance 0.1016)
			(thermal_gap 0.1016)
		)
		(pad "9" thru_hole circle
			(at 1.27 0.762 270)
			(size 0.7112 0.7112)
			(drill 0.4064)
			(layers "*.Cu" "*.Mask")
			(remove_unused_layers no)
			(net "GND")
			(clearance 0.1016)
			(thermal_gap 0.1016)
		)
		(pad "10" thru_hole circle
			(at -0.0254 0.762 270)
			(size 0.7112 0.7112)
			(drill 0.4064)
			(layers "*.Cu" "*.Mask")
			(remove_unused_layers no)
			(net "GND")
			(clearance 0.1016)
			(thermal_gap 0.1016)
		)
		(pad "11" thru_hole circle
			(at -1.27 0.762 270)
			(size 0.7112 0.7112)
			(drill 0.4064)
			(layers "*.Cu" "*.Mask")
			(remove_unused_layers no)
			(net "GND")
			(clearance 0.1016)
			(thermal_gap 0.1016)
		)
		(pad "12" thru_hole circle
			(at -1.27 -0.4572 270)
			(size 0.7112 0.7112)
			(drill 0.4064)
			(layers "*.Cu" "*.Mask")
			(remove_unused_layers no)
			(net "GND")
			(clearance 0.1016)
			(thermal_gap 0.1016)
		)
	)
)
